(kicad_pcb
	(version 20260206)
	(generator "pcbnew")
	(generator_version "10.0")
	(general
		(thickness 1.6)
		(legacy_teardrops no)
	)
	(paper "A4")
	(title_block
		(title "01162023_DA0F0TEBIF0_F0T_Expander_BD_F_brd_V02_OCP.brd")
		(comment 1 "Grand Teton / footprints 1850-1854 of 9728")
	)
	(layers
		(0 "F.Cu" signal "TOP")
		(4 "In1.Cu" signal "GND")
		(6 "In2.Cu" signal "VCC")
		(8 "In3.Cu" signal "VCC1")
		(10 "In4.Cu" signal "GND1")
		(12 "In5.Cu" signal "IN1")
		(14 "In6.Cu" signal "GND2")
		(16 "In7.Cu" signal "IN2")
		(18 "In8.Cu" signal "GND3")
		(20 "In9.Cu" signal "IN3")
		(22 "In10.Cu" signal "GND4")
		(24 "In11.Cu" signal "IN4")
		(26 "In12.Cu" signal "GND5")
		(28 "In13.Cu" signal "IN5")
		(30 "In14.Cu" signal "GND6")
		(32 "In15.Cu" signal "IN6")
		(34 "In16.Cu" signal "GND7")
		(2 "B.Cu" signal "BOTTOM")
		(9 "F.Adhes" user "F.Adhesive")
		(11 "B.Adhes" user "B.Adhesive")
		(13 "F.Paste" user "Package Geometry/Pastemask Top")
		(15 "B.Paste" user "Package Geometry/Pastemask Bottom")
		(5 "F.SilkS" user "Ref Des/Silkscreen Top")
		(7 "B.SilkS" user "Ref Des/Silkscreen Bottom")
		(1 "F.Mask" user "Board Geometry/Soldermask Top")
		(3 "B.Mask" user "Board Geometry/Soldermask Bottom")
		(17 "Dwgs.User" user "User.Drawings")
		(19 "Cmts.User" user "User.Comments")
		(21 "Eco1.User" user "User.Eco1")
		(23 "Eco2.User" user "User.Eco2")
		(25 "Edge.Cuts" user "Board Geometry/Outline")
		(27 "Margin" user)
		(31 "F.CrtYd" user "Package Geometry/Place Bound Top")
		(29 "B.CrtYd" user "Package Geometry/Place Bound Bottom")
		(35 "F.Fab" user "Ref Des/Assembly Top")
		(33 "B.Fab" user "Ref Des/Assembly Bottom")
	)
	(footprint ""
		(layer "F.Cu")
		(at 210.054444 -122.889264 180)
		(property "Reference" "PC448"
			(at 0 0 180)
			(layer "F.SilkS")
			(hide yes)
			(effects
				(font
					(size 1.27 1.27)
				)
			)
		)
		(property "Value" ""
			(at 0 0 180)
			(layer "F.Fab")
			(effects
				(font
					(size 1.27 1.27)
				)
			)
		)
		(duplicate_pad_numbers_are_jumpers no)
		(fp_line
			(start 0.7874 0.4064)
			(end -0.7874 0.4064)
			(stroke
				(width 0.1524)
				(type default)
			)
			(layer "F.SilkS")
		)
		(fp_line
			(start 0.7874 -0.4064)
			(end 0.7874 0.4064)
			(stroke
				(width 0.1524)
				(type default)
			)
			(layer "F.SilkS")
		)
		(fp_line
			(start -0.7874 0.4064)
			(end -0.7874 -0.4064)
			(stroke
				(width 0.1524)
				(type default)
			)
			(layer "F.SilkS")
		)
		(fp_line
			(start -0.7874 -0.4064)
			(end 0.7874 -0.4064)
			(stroke
				(width 0.1524)
				(type default)
			)
			(layer "F.SilkS")
		)
		(fp_line
			(start 0.67945 0.3048)
			(end 0.120396 0.3048)
			(stroke
				(width 0.1)
				(type default)
			)
			(layer "F.Fab")
		)
		(fp_line
			(start 0.67945 -0.3048)
			(end 0.67945 0.3048)
			(stroke
				(width 0.1)
				(type default)
			)
			(layer "F.Fab")
		)
		(fp_line
			(start 0.12065 -0.2794)
			(end 0.12065 -0.3048)
			(stroke
				(width 0.1)
				(type default)
			)
			(layer "F.Fab")
		)
		(fp_line
			(start 0.12065 -0.3048)
			(end 0.67945 -0.3048)
			(stroke
				(width 0.1)
				(type default)
			)
			(layer "F.Fab")
		)
		(fp_line
			(start 0.120396 0.3048)
			(end 0.120396 0.2794)
			(stroke
				(width 0.1)
				(type default)
			)
			(layer "F.Fab")
		)
		(fp_line
			(start 0.120396 0.2794)
			(end -0.12065 0.2794)
			(stroke
				(width 0.1)
				(type default)
			)
			(layer "F.Fab")
		)
		(fp_line
			(start -0.12065 0.3048)
			(end -0.67945 0.3048)
			(stroke
				(width 0.1)
				(type default)
			)
			(layer "F.Fab")
		)
		(fp_line
			(start -0.12065 0.2794)
			(end -0.12065 0.3048)
			(stroke
				(width 0.1)
				(type default)
			)
			(layer "F.Fab")
		)
		(fp_line
			(start -0.12065 -0.2794)
			(end 0.12065 -0.2794)
			(stroke
				(width 0.1)
				(type default)
			)
			(layer "F.Fab")
		)
		(fp_line
			(start -0.12065 -0.305054)
			(end -0.12065 -0.2794)
			(stroke
				(width 0.1)
				(type default)
			)
			(layer "F.Fab")
		)
		(fp_line
			(start -0.67945 0.3048)
			(end -0.67945 -0.305054)
			(stroke
				(width 0.1)
				(type default)
			)
			(layer "F.Fab")
		)
		(fp_line
			(start -0.67945 -0.305054)
			(end -0.12065 -0.305054)
			(stroke
				(width 0.1)
				(type default)
			)
			(layer "F.Fab")
		)
		(pad "1" smd circle
			(at -0.40005 0 180)
			(size 0 0)
			(layers "F.Cu" "F.Mask" "F.Paste")
			(net "P3V3_AUX")
		)
		(pad "2" smd circle
			(at 0.40005 0 180)
			(size 0 0)
			(layers "F.Cu" "F.Mask" "F.Paste")
			(net "GND")
		)
	)
	(footprint ""
		(layer "F.Cu")
		(at 250.407678 -152.71115 90)
		(property "Reference" "R728"
			(at 0 0 90)
			(layer "F.SilkS")
			(hide yes)
			(effects
				(font
					(size 1.27 1.27)
				)
			)
		)
		(property "Value" ""
			(at 0 0 90)
			(layer "F.Fab")
			(effects
				(font
					(size 1.27 1.27)
				)
			)
		)
		(duplicate_pad_numbers_are_jumpers no)
		(fp_line
			(start 0.7874 -0.4064)
			(end 0.7874 0.4064)
			(stroke
				(width 0.1524)
				(type default)
			)
			(layer "F.SilkS")
		)
		(fp_line
			(start -0.7874 -0.4064)
			(end 0.7874 -0.4064)
			(stroke
				(width 0.1524)
				(type default)
			)
			(layer "F.SilkS")
		)
		(fp_line
			(start 0.7874 0.4064)
			(end -0.7874 0.4064)
			(stroke
				(width 0.1524)
				(type default)
			)
			(layer "F.SilkS")
		)
		(fp_line
			(start -0.7874 0.4064)
			(end -0.7874 -0.4064)
			(stroke
				(width 0.1524)
				(type default)
			)
			(layer "F.SilkS")
		)
		(fp_line
			(start -0.12065 -0.305054)
			(end -0.12065 -0.2794)
			(stroke
				(width 0.1)
				(type default)
			)
			(layer "F.Fab")
		)
		(fp_line
			(start -0.67945 -0.305054)
			(end -0.12065 -0.305054)
			(stroke
				(width 0.1)
				(type default)
			)
			(layer "F.Fab")
		)
		(fp_line
			(start 0.67945 -0.3048)
			(end 0.67945 0.3048)
			(stroke
				(width 0.1)
				(type default)
			)
			(layer "F.Fab")
		)
		(fp_line
			(start 0.12065 -0.3048)
			(end 0.67945 -0.3048)
			(stroke
				(width 0.1)
				(type default)
			)
			(layer "F.Fab")
		)
		(fp_line
			(start 0.12065 -0.2794)
			(end 0.12065 -0.3048)
			(stroke
				(width 0.1)
				(type default)
			)
			(layer "F.Fab")
		)
		(fp_line
			(start -0.12065 -0.2794)
			(end 0.12065 -0.2794)
			(stroke
				(width 0.1)
				(type default)
			)
			(layer "F.Fab")
		)
		(fp_line
			(start 0.120396 0.2794)
			(end -0.12065 0.2794)
			(stroke
				(width 0.1)
				(type default)
			)
			(layer "F.Fab")
		)
		(fp_line
			(start -0.12065 0.2794)
			(end -0.12065 0.3048)
			(stroke
				(width 0.1)
				(type default)
			)
			(layer "F.Fab")
		)
		(fp_line
			(start 0.67945 0.3048)
			(end 0.120396 0.3048)
			(stroke
				(width 0.1)
				(type default)
			)
			(layer "F.Fab")
		)
		(fp_line
			(start 0.120396 0.3048)
			(end 0.120396 0.2794)
			(stroke
				(width 0.1)
				(type default)
			)
			(layer "F.Fab")
		)
		(fp_line
			(start -0.12065 0.3048)
			(end -0.67945 0.3048)
			(stroke
				(width 0.1)
				(type default)
			)
			(layer "F.Fab")
		)
		(fp_line
			(start -0.67945 0.3048)
			(end -0.67945 -0.305054)
			(stroke
				(width 0.1)
				(type default)
			)
			(layer "F.Fab")
		)
		(pad "1" smd circle
			(at -0.40005 0 90)
			(size 0 0)
			(layers "F.Cu" "F.Mask" "F.Paste")
			(net "NIC4_ADC_ALERT_N")
		)
		(pad "2" smd circle
			(at 0.40005 0 90)
			(size 0 0)
			(layers "F.Cu" "F.Mask" "F.Paste")
			(net "NIC_ADC_ALERT_N")
		)
	)
	(footprint ""
		(layer "F.Cu")
		(at 335.509362 -93.152214 90)
		(property "Reference" "R3511"
			(at 0 0 90)
			(layer "F.SilkS")
			(hide yes)
			(effects
				(font
					(size 1.27 1.27)
				)
			)
		)
		(property "Value" ""
			(at 0 0 90)
			(layer "F.Fab")
			(effects
				(font
					(size 1.27 1.27)
				)
			)
		)
		(duplicate_pad_numbers_are_jumpers no)
		(fp_line
			(start 0.7874 -0.4064)
			(end 0.7874 0.4064)
			(stroke
				(width 0.1524)
				(type default)
			)
			(layer "F.SilkS")
		)
		(fp_line
			(start -0.7874 -0.4064)
			(end 0.7874 -0.4064)
			(stroke
				(width 0.1524)
				(type default)
			)
			(layer "F.SilkS")
		)
		(fp_line
			(start 0.7874 0.4064)
			(end -0.7874 0.4064)
			(stroke
				(width 0.1524)
				(type default)
			)
			(layer "F.SilkS")
		)
		(fp_line
			(start -0.7874 0.4064)
			(end -0.7874 -0.4064)
			(stroke
				(width 0.1524)
				(type default)
			)
			(layer "F.SilkS")
		)
		(fp_line
			(start -0.12065 -0.305054)
			(end -0.12065 -0.2794)
			(stroke
				(width 0.1)
				(type default)
			)
			(layer "F.Fab")
		)
		(fp_line
			(start -0.67945 -0.305054)
			(end -0.12065 -0.305054)
			(stroke
				(width 0.1)
				(type default)
			)
			(layer "F.Fab")
		)
		(fp_line
			(start 0.67945 -0.3048)
			(end 0.67945 0.3048)
			(stroke
				(width 0.1)
				(type default)
			)
			(layer "F.Fab")
		)
		(fp_line
			(start 0.12065 -0.3048)
			(end 0.67945 -0.3048)
			(stroke
				(width 0.1)
				(type default)
			)
			(layer "F.Fab")
		)
		(fp_line
			(start 0.12065 -0.2794)
			(end 0.12065 -0.3048)
			(stroke
				(width 0.1)
				(type default)
			)
			(layer "F.Fab")
		)
		(fp_line
			(start -0.12065 -0.2794)
			(end 0.12065 -0.2794)
			(stroke
				(width 0.1)
				(type default)
			)
			(layer "F.Fab")
		)
		(fp_line
			(start 0.120396 0.2794)
			(end -0.12065 0.2794)
			(stroke
				(width 0.1)
				(type default)
			)
			(layer "F.Fab")
		)
		(fp_line
			(start -0.12065 0.2794)
			(end -0.12065 0.3048)
			(stroke
				(width 0.1)
				(type default)
			)
			(layer "F.Fab")
		)
		(fp_line
			(start 0.67945 0.3048)
			(end 0.120396 0.3048)
			(stroke
				(width 0.1)
				(type default)
			)
			(layer "F.Fab")
		)
		(fp_line
			(start 0.120396 0.3048)
			(end 0.120396 0.2794)
			(stroke
				(width 0.1)
				(type default)
			)
			(layer "F.Fab")
		)
		(fp_line
			(start -0.12065 0.3048)
			(end -0.67945 0.3048)
			(stroke
				(width 0.1)
				(type default)
			)
			(layer "F.Fab")
		)
		(fp_line
			(start -0.67945 0.3048)
			(end -0.67945 -0.305054)
			(stroke
				(width 0.1)
				(type default)
			)
			(layer "F.Fab")
		)
		(pad "1" smd circle
			(at -0.40005 0 90)
			(size 0 0)
			(layers "F.Cu" "F.Mask" "F.Paste")
			(net "PU_9ZXL0851_8_15_HBW")
		)
		(pad "2" smd circle
			(at 0.40005 0 90)
			(size 0 0)
			(layers "F.Cu" "F.Mask" "F.Paste")
			(net "GND")
		)
	)
	(footprint ""
		(layer "F.Cu")
		(at 268.220698 -333.104744)
		(property "Reference" "R6793"
			(at 0 0 0)
			(layer "F.SilkS")
			(hide yes)
			(effects
				(font
					(size 1.27 1.27)
				)
			)
		)
		(property "Value" ""
			(at 0 0 0)
			(layer "F.Fab")
			(effects
				(font
					(size 1.27 1.27)
				)
			)
		)
		(duplicate_pad_numbers_are_jumpers no)
		(fp_line
			(start -0.7874 -0.4064)
			(end 0.7874 -0.4064)
			(stroke
				(width 0.1524)
				(type default)
			)
			(layer "F.SilkS")
		)
		(fp_line
			(start -0.7874 0.4064)
			(end -0.7874 -0.4064)
			(stroke
				(width 0.1524)
				(type default)
			)
			(layer "F.SilkS")
		)
		(fp_line
			(start 0.7874 -0.4064)
			(end 0.7874 0.4064)
			(stroke
				(width 0.1524)
				(type default)
			)
			(layer "F.SilkS")
		)
		(fp_line
			(start 0.7874 0.4064)
			(end -0.7874 0.4064)
			(stroke
				(width 0.1524)
				(type default)
			)
			(layer "F.SilkS")
		)
		(fp_line
			(start -0.67945 -0.305054)
			(end -0.12065 -0.305054)
			(stroke
				(width 0.1)
				(type default)
			)
			(layer "F.Fab")
		)
		(fp_line
			(start -0.67945 0.3048)
			(end -0.67945 -0.305054)
			(stroke
				(width 0.1)
				(type default)
			)
			(layer "F.Fab")
		)
		(fp_line
			(start -0.12065 -0.305054)
			(end -0.12065 -0.2794)
			(stroke
				(width 0.1)
				(type default)
			)
			(layer "F.Fab")
		)
		(fp_line
			(start -0.12065 -0.2794)
			(end 0.12065 -0.2794)
			(stroke
				(width 0.1)
				(type default)
			)
			(layer "F.Fab")
		)
		(fp_line
			(start -0.12065 0.2794)
			(end -0.12065 0.3048)
			(stroke
				(width 0.1)
				(type default)
			)
			(layer "F.Fab")
		)
		(fp_line
			(start -0.12065 0.3048)
			(end -0.67945 0.3048)
			(stroke
				(width 0.1)
				(type default)
			)
			(layer "F.Fab")
		)
		(fp_line
			(start 0.120396 0.2794)
			(end -0.12065 0.2794)
			(stroke
				(width 0.1)
				(type default)
			)
			(layer "F.Fab")
		)
		(fp_line
			(start 0.120396 0.3048)
			(end 0.120396 0.2794)
			(stroke
				(width 0.1)
				(type default)
			)
			(layer "F.Fab")
		)
		(fp_line
			(start 0.12065 -0.3048)
			(end 0.67945 -0.3048)
			(stroke
				(width 0.1)
				(type default)
			)
			(layer "F.Fab")
		)
		(fp_line
			(start 0.12065 -0.2794)
			(end 0.12065 -0.3048)
			(stroke
				(width 0.1)
				(type default)
			)
			(layer "F.Fab")
		)
		(fp_line
			(start 0.67945 -0.3048)
			(end 0.67945 0.3048)
			(stroke
				(width 0.1)
				(type default)
			)
			(layer "F.Fab")
		)
		(fp_line
			(start 0.67945 0.3048)
			(end 0.120396 0.3048)
			(stroke
				(width 0.1)
				(type default)
			)
			(layer "F.Fab")
		)
		(pad "1" smd circle
			(at -0.40005 0)
			(size 0 0)
			(layers "F.Cu" "F.Mask" "F.Paste")
			(net "P3V3_AUX")
		)
		(pad "2" smd circle
			(at 0.40005 0)
			(size 0 0)
			(layers "F.Cu" "F.Mask" "F.Paste")
			(net "A_HSC_LOW_GATE")
		)
	)
	(footprint ""
		(layer "F.Cu")
		(at 244.696996 -277.791926 180)
		(property "Reference" "U94"
			(at -0.799338 -4.270756 0)
			(unlocked yes)
			(layer "F.SilkS")
			(effects
				(font
					(size 0.7874 0.5842)
					(thickness 0.1524)
				)
			)
		)
		(property "Value" ""
			(at 0 0 180)
			(layer "F.Fab")
			(effects
				(font
					(size 1.27 1.27)
				)
			)
		)
		(duplicate_pad_numbers_are_jumpers no)
		(fp_line
			(start 1.500124 1.500124)
			(end 1.004062 1.500124)
			(stroke
				(width 0.1524)
				(type default)
			)
			(layer "F.SilkS")
		)
		(fp_line
			(start 1.500124 1.004062)
			(end 1.500124 1.500124)
			(stroke
				(width 0.1524)
				(type default)
			)
			(layer "F.SilkS")
		)
		(fp_line
			(start 1.500124 -1.500124)
			(end 1.500124 -1.004062)
			(stroke
				(width 0.1524)
				(type default)
			)
			(layer "F.SilkS")
		)
		(fp_line
			(start 1.004062 -1.500124)
			(end 1.500124 -1.500124)
			(stroke
				(width 0.1524)
				(type default)
			)
			(layer "F.SilkS")
		)
		(fp_line
			(start -1.004062 1.500124)
			(end -1.500124 1.500124)
			(stroke
				(width 0.1524)
				(type default)
			)
			(layer "F.SilkS")
		)
		(fp_line
			(start -1.500124 1.500124)
			(end -1.500124 1.004062)
			(stroke
				(width 0.1524)
				(type default)
			)
			(layer "F.SilkS")
		)
		(fp_line
			(start -1.500124 -1.004062)
			(end -1.500124 -1.500124)
			(stroke
				(width 0.1524)
				(type default)
			)
			(layer "F.SilkS")
		)
		(fp_line
			(start -1.500124 -1.500124)
			(end -1.004062 -1.500124)
			(stroke
				(width 0.1524)
				(type default)
			)
			(layer "F.SilkS")
		)
		(fp_poly
			(pts
				(xy -1.153414 -2.31267) (xy -2.169414 -2.31267) (xy -1.661414 -1.29667)
			)
			(stroke
				(width 0)
				(type default)
			)
			(fill yes)
			(layer "F.SilkS")
		)
		(fp_line
			(start 1.500124 1.500124)
			(end -1.500124 1.500124)
			(stroke
				(width 0.1)
				(type default)
			)
			(layer "F.Fab")
		)
		(fp_line
			(start 1.500124 -1.500124)
			(end 1.500124 1.500124)
			(stroke
				(width 0.1)
				(type default)
			)
			(layer "F.Fab")
		)
		(fp_line
			(start -1.500124 1.500124)
			(end -1.500124 -1.500124)
			(stroke
				(width 0.1)
				(type default)
			)
			(layer "F.Fab")
		)
		(fp_line
			(start -1.500124 -1.500124)
			(end 1.500124 -1.500124)
			(stroke
				(width 0.1)
				(type default)
			)
			(layer "F.Fab")
		)
		(fp_poly
			(pts
				(xy -2.847848 -1.258062) (xy -2.847848 -0.242062) (xy -1.831848 -0.750062)
			)
			(stroke
				(width 0)
				(type default)
			)
			(fill yes)
			(layer "F.Fab")
		)
		(pad "1" smd rect
			(at -1.400048 -0.750062 90)
			(size 0.2286 0.6096)
			(layers "F.Cu" "F.Mask" "F.Paste")
			(net "PEX2_P1V25_ADC_A1")
		)
		(pad "2" smd rect
			(at -1.400048 -0.249936 90)
			(size 0.2286 0.6096)
			(layers "F.Cu" "F.Mask" "F.Paste")
			(net "PEX2_P1V25_ADC_A0")
		)
		(pad "3" smd rect
			(at -1.400048 0.249936 90)
			(size 0.2286 0.6096)
			(layers "F.Cu" "F.Mask" "F.Paste")
			(net "PEX2_P1V25_ADC_ALERT_N")
		)
		(pad "4" smd rect
			(at -1.400048 0.750062 90)
			(size 0.2286 0.6096)
			(layers "F.Cu" "F.Mask" "F.Paste")
			(net "SMB_PEX2_P1V25_ADC_SDA")
		)
		(pad "5" smd rect
			(at -0.750062 1.400048 180)
			(size 0.2286 0.6096)
			(layers "F.Cu" "F.Mask" "F.Paste")
			(net "SMB_PEX2_P1V25_ADC_SCL")
		)
		(pad "6" smd rect
			(at -0.249936 1.400048 180)
			(size 0.2286 0.6096)
			(layers "F.Cu" "F.Mask" "F.Paste")
			(net "Net_8606")
		)
		(pad "7" smd rect
			(at 0.249936 1.400048 180)
			(size 0.2286 0.6096)
			(layers "F.Cu" "F.Mask" "F.Paste")
			(net "Net_8605")
		)
		(pad "8" smd rect
			(at 0.750062 1.400048 180)
			(size 0.2286 0.6096)
			(layers "F.Cu" "F.Mask" "F.Paste")
			(net "Net_8604")
		)
		(pad "9" smd rect
			(at 1.400048 0.750062 90)
			(size 0.2286 0.6096)
			(layers "F.Cu" "F.Mask" "F.Paste")
			(net "P3V3_AUX")
		)
		(pad "10" smd rect
			(at 1.400048 0.249936 90)
			(size 0.2286 0.6096)
			(layers "F.Cu" "F.Mask" "F.Paste")
			(net "GND")
		)
		(pad "11" smd rect
			(at 1.400048 -0.249936 90)
			(size 0.2286 0.6096)
			(layers "F.Cu" "F.Mask" "F.Paste")
			(net "P1V25_PEX2_R")
		)
		(pad "12" smd rect
			(at 1.400048 -0.750062 90)
			(size 0.2286 0.6096)
			(layers "F.Cu" "F.Mask" "F.Paste")
			(net "P12V_PEX2_P1V25_VIN_N")
		)
		(pad "13" smd rect
			(at 0.750062 -1.400048 180)
			(size 0.2286 0.6096)
			(layers "F.Cu" "F.Mask" "F.Paste")
			(net "P12V_PEX2_P1V25_VIN_P")
		)
		(pad "14" smd rect
			(at 0.249936 -1.400048 180)
			(size 0.2286 0.6096)
			(layers "F.Cu" "F.Mask" "F.Paste")
			(net "Net_8603")
		)
		(pad "15" smd rect
			(at -0.249936 -1.400048 180)
			(size 0.2286 0.6096)
			(layers "F.Cu" "F.Mask" "F.Paste")
			(net "Net_8602")
		)
		(pad "16" smd rect
			(at -0.750062 -1.400048 180)
			(size 0.2286 0.6096)
			(layers "F.Cu" "F.Mask" "F.Paste")
			(net "Net_8601")
		)
		(pad "TH" smd rect
			(at 0 0 180)
			(size 1.7018 1.7018)
			(layers "F.Cu" "F.Mask" "F.Paste")
			(net "GND")
		)
		(zone
			(layer "F.Cu")
			(hatch none 0.5)
			(connect_pads
				(clearance 0)
			)
			(min_thickness 0.25)
			(keepout
				(tracks not_allowed)
				(vias allowed)
				(pads allowed)
				(copperpour not_allowed)
				(footprints allowed)
			)
			(placement
				(enabled no)
				(sheetname "")
			)
			(fill
				(thermal_gap 0.5)
				(thermal_bridge_width 0.5)
				(island_removal_mode 0)
			)
			(polygon
				(pts
					(xy 245.741444 -277.766526) (xy 245.741444 -276.747478) (xy 243.652548 -276.747478) (xy 243.652548 -278.836374)
					(xy 245.741444 -278.836374) (xy 245.741444 -277.791926) (xy 245.598696 -277.791926) (xy 245.598696 -278.693626)
					(xy 243.795296 -278.693626) (xy 243.795296 -276.890226) (xy 245.598696 -276.890226) (xy 245.598696 -277.766526)
				)
			)
		)
	)
)
